(kicad_pcb
	(version 20260206)
	(generator "pcbnew")
	(generator_version "10.0")
	(general
		(thickness 1.6)
		(legacy_teardrops no)
	)
	(paper "A4")
	(title_block
		(title "Wiwynn_Tioga_Pass_MB.brd")
		(comment 1 "Tioga Pass / footprints 2807-2813 of 4770")
	)
	(layers
		(0 "F.Cu" signal "TOP")
		(4 "In1.Cu" signal "L2GND")
		(6 "In2.Cu" signal "L3")
		(8 "In3.Cu" signal "L4GND")
		(10 "In4.Cu" signal "L5")
		(12 "In5.Cu" signal "L6GND")
		(14 "In6.Cu" signal "L7VCC")
		(16 "In7.Cu" signal "L8VCC")
		(18 "In8.Cu" signal "L9GND")
		(20 "In9.Cu" signal "L10")
		(22 "In10.Cu" signal "L11GND")
		(24 "In11.Cu" signal "L12")
		(26 "In12.Cu" signal "L13GND")
		(2 "B.Cu" signal "BOTTOM")
		(9 "F.Adhes" user "F.Adhesive")
		(11 "B.Adhes" user "B.Adhesive")
		(13 "F.Paste" user "Package Geometry/Pastemask Top")
		(15 "B.Paste" user "Package Geometry/Pastemask Bottom")
		(5 "F.SilkS" user "Ref Des/Silkscreen Top")
		(7 "B.SilkS" user "Ref Des/Silkscreen Bottom")
		(1 "F.Mask" user "Board Geometry/Soldermask Top")
		(3 "B.Mask" user "Board Geometry/Soldermask Bottom")
		(17 "Dwgs.User" user "User.Drawings")
		(19 "Cmts.User" user "User.Comments")
		(21 "Eco1.User" user "User.Eco1")
		(23 "Eco2.User" user "User.Eco2")
		(25 "Edge.Cuts" user "Board Geometry/Outline")
		(27 "Margin" user)
		(31 "F.CrtYd" user "Package Geometry/Place Bound Top")
		(29 "B.CrtYd" user "Package Geometry/Place Bound Bottom")
		(35 "F.Fab" user "Ref Des/Assembly Top")
		(33 "B.Fab" user "Ref Des/Assembly Bottom")
	)
	(footprint ""
		(layer "B.Cu")
		(at 377.144788 -70.695058)
		(property "Reference" "C2P8"
			(at 0 0 0)
			(layer "B.SilkS")
			(hide yes)
			(effects
				(font
					(size 1.27 1.27)
				)
				(justify mirror)
			)
		)
		(property "Value" ""
			(at 0 0 0)
			(layer "B.Fab")
			(effects
				(font
					(size 1.27 1.27)
				)
				(justify mirror)
			)
		)
		(duplicate_pad_numbers_are_jumpers no)
		(fp_rect
			(start 0.2794 0.9144)
			(end -0.2794 -0.1143)
			(stroke
				(width 0)
				(type default)
			)
			(fill no)
			(layer "B.CrtYd")
		)
		(fp_line
			(start -0.2794 -0.1143)
			(end -0.2794 0.9144)
			(stroke
				(width 0.1)
				(type default)
			)
			(layer "B.Fab")
		)
		(fp_line
			(start -0.2794 0.9144)
			(end 0.2794 0.9144)
			(stroke
				(width 0.1)
				(type default)
			)
			(layer "B.Fab")
		)
		(fp_line
			(start 0.2794 -0.1143)
			(end -0.2794 -0.1143)
			(stroke
				(width 0.1)
				(type default)
			)
			(layer "B.Fab")
		)
		(fp_line
			(start 0.2794 0.9144)
			(end 0.2794 -0.1143)
			(stroke
				(width 0.1)
				(type default)
			)
			(layer "B.Fab")
		)
		(pad "1" smd custom
			(at 0 0 270)
			(size 0.10414 0.10414)
			(layers "B.Cu" "B.Mask" "B.Paste")
			(net "P3V3_STBY")
			(options
				(clearance outline)
				(anchor circle)
			)
			(primitives
				(gr_poly
					(pts
						(xy -0.20828 -0.08636) (xy -0.20828 0.08636) (xy -0.08636 0.20828) (xy 0.086614 0.20828) (xy 0.20828 0.086614)
						(xy 0.20828 -0.08636) (xy 0.08636 -0.20828) (xy -0.08636 -0.20828)
					)
					(width 0)
					(fill yes)
				)
			)
		)
		(pad "2" smd custom
			(at 0 0.8001 270)
			(size 0.10414 0.10414)
			(layers "B.Cu" "B.Mask" "B.Paste")
			(net "GND")
			(options
				(clearance outline)
				(anchor circle)
			)
			(primitives
				(gr_poly
					(pts
						(xy -0.20828 -0.08636) (xy -0.20828 0.08636) (xy -0.08636 0.20828) (xy 0.086614 0.20828) (xy 0.20828 0.086614)
						(xy 0.20828 -0.08636) (xy 0.08636 -0.20828) (xy -0.08636 -0.20828)
					)
					(width 0)
					(fill yes)
				)
			)
		)
		(zone
			(layer "B.Cu")
			(hatch none 0.5)
			(connect_pads
				(clearance 0)
			)
			(min_thickness 0.25)
			(keepout
				(tracks allowed)
				(vias not_allowed)
				(pads allowed)
				(copperpour not_allowed)
				(footprints allowed)
			)
			(placement
				(enabled no)
				(sheetname "")
			)
			(fill
				(thermal_gap 0.5)
				(thermal_bridge_width 0.5)
				(island_removal_mode 0)
			)
			(polygon
				(pts
					(xy 377.232418 -70.485508) (xy 377.232418 -70.104508) (xy 377.057158 -70.104508) (xy 377.056904 -70.485508)
				)
			)
		)
		(zone
			(layer "B.Cu")
			(hatch none 0.5)
			(connect_pads
				(clearance 0)
			)
			(min_thickness 0.25)
			(keepout
				(tracks not_allowed)
				(vias allowed)
				(pads allowed)
				(copperpour not_allowed)
				(footprints allowed)
			)
			(placement
				(enabled no)
				(sheetname "")
			)
			(fill
				(thermal_gap 0.5)
				(thermal_bridge_width 0.5)
				(island_removal_mode 0)
			)
			(polygon
				(pts
					(xy 377.232418 -70.485508) (xy 377.232418 -70.104508) (xy 377.057158 -70.104508) (xy 377.056904 -70.485508)
				)
			)
		)
	)
	(footprint ""
		(layer "B.Cu")
		(at 349.489014 -122.459242 -90)
		(property "Reference" "C3M14"
			(at 0 0 90)
			(layer "B.SilkS")
			(hide yes)
			(effects
				(font
					(size 1.27 1.27)
				)
				(justify mirror)
			)
		)
		(property "Value" ""
			(at 0 0 90)
			(layer "B.Fab")
			(effects
				(font
					(size 1.27 1.27)
				)
				(justify mirror)
			)
		)
		(duplicate_pad_numbers_are_jumpers no)
		(fp_poly
			(pts
				(xy -0.3048 -0.1016) (xy -0.3048 0.9906) (xy 0.3048 0.9906) (xy 0.3048 -0.1016)
			)
			(stroke
				(width 0)
				(type default)
			)
			(fill no)
			(layer "B.CrtYd")
		)
		(fp_line
			(start -0.3048 0.9906)
			(end -0.3048 -0.1016)
			(stroke
				(width 0.1)
				(type default)
			)
			(layer "B.Fab")
		)
		(fp_line
			(start 0.3048 0.9906)
			(end -0.3048 0.9906)
			(stroke
				(width 0.1)
				(type default)
			)
			(layer "B.Fab")
		)
		(fp_line
			(start -0.3048 -0.1016)
			(end 0.3048 -0.1016)
			(stroke
				(width 0.1)
				(type default)
			)
			(layer "B.Fab")
		)
		(fp_line
			(start 0.3048 -0.1016)
			(end 0.3048 0.9906)
			(stroke
				(width 0.1)
				(type default)
			)
			(layer "B.Fab")
		)
		(pad "1" smd rect
			(at 0 0 90)
			(size 0.508 0.508)
			(layers "B.Cu" "B.Mask" "B.Paste")
			(net "P3E_CPU0_PE1_PCH_R_RXN<13>")
		)
		(pad "2" smd rect
			(at 0 0.889 90)
			(size 0.508 0.508)
			(layers "B.Cu" "B.Mask" "B.Paste")
			(net "P3E_CPU0_PE1_PCH_RXN<13>")
		)
		(zone
			(layer "B.Cu")
			(hatch none 0.5)
			(connect_pads
				(clearance 0)
			)
			(min_thickness 0.25)
			(keepout
				(tracks not_allowed)
				(vias allowed)
				(pads allowed)
				(copperpour not_allowed)
				(footprints allowed)
			)
			(placement
				(enabled no)
				(sheetname "")
			)
			(fill
				(thermal_gap 0.5)
				(thermal_bridge_width 0.5)
				(island_removal_mode 0)
			)
			(polygon
				(pts
					(xy 348.854014 -122.205242) (xy 348.854014 -122.713242) (xy 349.235014 -122.713242) (xy 349.235014 -122.205242)
				)
			)
		)
		(zone
			(layer "B.Cu")
			(hatch none 0.5)
			(connect_pads
				(clearance 0)
			)
			(min_thickness 0.25)
			(keepout
				(tracks allowed)
				(vias not_allowed)
				(pads allowed)
				(copperpour not_allowed)
				(footprints allowed)
			)
			(placement
				(enabled no)
				(sheetname "")
			)
			(fill
				(thermal_gap 0.5)
				(thermal_bridge_width 0.5)
				(island_removal_mode 0)
			)
			(polygon
				(pts
					(xy 349.235014 -122.205242) (xy 349.235014 -122.713242) (xy 348.854014 -122.713242) (xy 348.854014 -122.205242)
				)
			)
		)
	)
	(footprint ""
		(layer "B.Cu")
		(at 403.352 -36.068)
		(property "Reference" "R25W86"
			(at 0.8382 -0.67818 0)
			(unlocked yes)
			(layer "B.SilkS")
			(effects
				(font
					(size 0.4064 0.254)
					(thickness 0.1524)
				)
				(justify left mirror)
			)
		)
		(property "Value" ""
			(at 0 0 0)
			(layer "B.Fab")
			(effects
				(font
					(size 1.27 1.27)
				)
				(justify mirror)
			)
		)
		(duplicate_pad_numbers_are_jumpers no)
		(fp_poly
			(pts
				(xy 0.2794 -0.1016) (xy -0.2794 -0.1016) (xy -0.2794 0.9906) (xy 0.2794 0.9906)
			)
			(stroke
				(width 0)
				(type default)
			)
			(fill no)
			(layer "B.CrtYd")
		)
		(fp_line
			(start -0.2794 -0.1016)
			(end 0.2794 -0.1016)
			(stroke
				(width 0.1)
				(type default)
			)
			(layer "B.Fab")
		)
		(fp_line
			(start -0.2794 0.9906)
			(end -0.2794 -0.1016)
			(stroke
				(width 0.1)
				(type default)
			)
			(layer "B.Fab")
		)
		(fp_line
			(start 0.2794 -0.1016)
			(end 0.2794 0.9906)
			(stroke
				(width 0.1)
				(type default)
			)
			(layer "B.Fab")
		)
		(fp_line
			(start 0.2794 0.9906)
			(end -0.2794 0.9906)
			(stroke
				(width 0.1)
				(type default)
			)
			(layer "B.Fab")
		)
		(pad "1" smd rect
			(at 0 0 180)
			(size 0.508 0.508)
			(layers "B.Cu" "B.Mask" "B.Paste")
			(net "RMII_BMC_OCP_TXD0_R")
		)
		(pad "2" smd rect
			(at 0 0.889 180)
			(size 0.508 0.508)
			(layers "B.Cu" "B.Mask" "B.Paste")
			(net "RMII_BMC_OCP_TXD0")
		)
		(zone
			(layer "B.Cu")
			(hatch none 0.5)
			(connect_pads
				(clearance 0)
			)
			(min_thickness 0.25)
			(keepout
				(tracks allowed)
				(vias not_allowed)
				(pads allowed)
				(copperpour not_allowed)
				(footprints allowed)
			)
			(placement
				(enabled no)
				(sheetname "")
			)
			(fill
				(thermal_gap 0.5)
				(thermal_bridge_width 0.5)
				(island_removal_mode 0)
			)
			(polygon
				(pts
					(xy 403.606 -35.814) (xy 403.098 -35.814) (xy 403.098 -35.433) (xy 403.606 -35.433)
				)
			)
		)
		(zone
			(layer "B.Cu")
			(hatch none 0.5)
			(connect_pads
				(clearance 0)
			)
			(min_thickness 0.25)
			(keepout
				(tracks not_allowed)
				(vias allowed)
				(pads allowed)
				(copperpour not_allowed)
				(footprints allowed)
			)
			(placement
				(enabled no)
				(sheetname "")
			)
			(fill
				(thermal_gap 0.5)
				(thermal_bridge_width 0.5)
				(island_removal_mode 0)
			)
			(polygon
				(pts
					(xy 403.606 -35.433) (xy 403.098 -35.433) (xy 403.098 -35.814) (xy 403.606 -35.814)
				)
			)
		)
	)
	(footprint ""
		(layer "B.Cu")
		(at 494.665 -135.2804 -90)
		(property "Reference" "Q6W4"
			(at 0.229362 -1.59512 270)
			(unlocked yes)
			(layer "B.SilkS")
			(effects
				(font
					(size 1.27 0.9652)
					(thickness 0.1524)
				)
				(justify left mirror)
			)
		)
		(property "Value" ""
			(at 0 0 90)
			(layer "B.Fab")
			(effects
				(font
					(size 1.27 1.27)
				)
				(justify mirror)
			)
		)
		(duplicate_pad_numbers_are_jumpers no)
		(fp_line
			(start -1.778 2.4765)
			(end -1.778 1.5875)
			(stroke
				(width 0.1524)
				(type default)
			)
			(layer "B.SilkS")
		)
		(fp_line
			(start -0.9525 2.4765)
			(end -1.778 2.4765)
			(stroke
				(width 0.1524)
				(type default)
			)
			(layer "B.SilkS")
		)
		(fp_line
			(start -0.381 0.635)
			(end -0.381 1.27)
			(stroke
				(width 0.1524)
				(type default)
			)
			(layer "B.SilkS")
		)
		(fp_line
			(start -1.778 -0.5715)
			(end -1.778 0.3175)
			(stroke
				(width 0.1524)
				(type default)
			)
			(layer "B.SilkS")
		)
		(fp_line
			(start -0.9525 -0.5715)
			(end -1.778 -0.5715)
			(stroke
				(width 0.1524)
				(type default)
			)
			(layer "B.SilkS")
		)
		(fp_circle
			(center 0.51816 -0.82423)
			(end 0.51816 -0.95123)
			(stroke
				(width 0.254)
				(type default)
			)
			(fill no)
			(layer "B.SilkS")
		)
		(fp_poly
			(pts
				(xy -1.778 2.4765) (xy -0.381 2.4765) (xy -0.381 -0.5715) (xy -1.778 -0.5715)
			)
			(stroke
				(width 0)
				(type default)
			)
			(fill no)
			(layer "B.CrtYd")
		)
		(fp_line
			(start -1.778 2.4765)
			(end -1.778 -0.5715)
			(stroke
				(width 0.1)
				(type default)
			)
			(layer "B.Fab")
		)
		(fp_line
			(start -0.381 2.4765)
			(end -1.778 2.4765)
			(stroke
				(width 0.1)
				(type default)
			)
			(layer "B.Fab")
		)
		(fp_line
			(start -1.778 -0.5715)
			(end -0.381 -0.5715)
			(stroke
				(width 0.1)
				(type default)
			)
			(layer "B.Fab")
		)
		(fp_line
			(start -0.381 -0.5715)
			(end -0.381 2.4765)
			(stroke
				(width 0.1)
				(type default)
			)
			(layer "B.Fab")
		)
		(fp_circle
			(center 0.9525 -0.9271)
			(end 0.9525 -1.0541)
			(stroke
				(width 0.254)
				(type default)
			)
			(fill no)
			(layer "B.Fab")
		)
		(pad "1" smd rect
			(at 0 0 90)
			(size 1.143 0.508)
			(layers "B.Cu" "B.Mask" "B.Paste")
			(net "DEBUG_CARD2_PRSNT")
		)
		(pad "2" smd rect
			(at 0 1.905 90)
			(size 1.143 0.508)
			(layers "B.Cu" "B.Mask" "B.Paste")
			(net "GND")
		)
		(pad "3" smd rect
			(at -2.159 0.9525 90)
			(size 1.143 0.508)
			(layers "B.Cu" "B.Mask" "B.Paste")
			(net "FM_POST_CARD_PRES_BMC_N")
		)
	)
	(footprint ""
		(layer "B.Cu")
		(at 22.225 -81.534)
		(property "Reference" "C9P6"
			(at 0 0 0)
			(layer "B.SilkS")
			(hide yes)
			(effects
				(font
					(size 1.27 1.27)
				)
				(justify mirror)
			)
		)
		(property "Value" ""
			(at 0 0 0)
			(layer "B.Fab")
			(effects
				(font
					(size 1.27 1.27)
				)
				(justify mirror)
			)
		)
		(duplicate_pad_numbers_are_jumpers no)
		(fp_poly
			(pts
				(xy -0.3048 -0.1016) (xy -0.3048 0.9906) (xy 0.3048 0.9906) (xy 0.3048 -0.1016)
			)
			(stroke
				(width 0)
				(type default)
			)
			(fill no)
			(layer "B.CrtYd")
		)
		(fp_line
			(start -0.3048 -0.1016)
			(end 0.3048 -0.1016)
			(stroke
				(width 0.1)
				(type default)
			)
			(layer "B.Fab")
		)
		(fp_line
			(start -0.3048 0.9906)
			(end -0.3048 -0.1016)
			(stroke
				(width 0.1)
				(type default)
			)
			(layer "B.Fab")
		)
		(fp_line
			(start 0.3048 -0.1016)
			(end 0.3048 0.9906)
			(stroke
				(width 0.1)
				(type default)
			)
			(layer "B.Fab")
		)
		(fp_line
			(start 0.3048 0.9906)
			(end -0.3048 0.9906)
			(stroke
				(width 0.1)
				(type default)
			)
			(layer "B.Fab")
		)
		(pad "1" smd rect
			(at 0 0 180)
			(size 0.508 0.508)
			(layers "B.Cu" "B.Mask" "B.Paste")
			(net "P12V_STBY")
		)
		(pad "2" smd rect
			(at 0 0.889 180)
			(size 0.508 0.508)
			(layers "B.Cu" "B.Mask" "B.Paste")
			(net "AGND_HSC")
		)
		(zone
			(layer "B.Cu")
			(hatch none 0.5)
			(connect_pads
				(clearance 0)
			)
			(min_thickness 0.25)
			(keepout
				(tracks allowed)
				(vias not_allowed)
				(pads allowed)
				(copperpour not_allowed)
				(footprints allowed)
			)
			(placement
				(enabled no)
				(sheetname "")
			)
			(fill
				(thermal_gap 0.5)
				(thermal_bridge_width 0.5)
				(island_removal_mode 0)
			)
			(polygon
				(pts
					(xy 22.479 -81.28) (xy 21.971 -81.28) (xy 21.971 -80.899) (xy 22.479 -80.899)
				)
			)
		)
		(zone
			(layer "B.Cu")
			(hatch none 0.5)
			(connect_pads
				(clearance 0)
			)
			(min_thickness 0.25)
			(keepout
				(tracks not_allowed)
				(vias allowed)
				(pads allowed)
				(copperpour not_allowed)
				(footprints allowed)
			)
			(placement
				(enabled no)
				(sheetname "")
			)
			(fill
				(thermal_gap 0.5)
				(thermal_bridge_width 0.5)
				(island_removal_mode 0)
			)
			(polygon
				(pts
					(xy 22.479 -80.899) (xy 21.971 -80.899) (xy 21.971 -81.28) (xy 22.479 -81.28)
				)
			)
		)
	)
	(footprint ""
		(layer "B.Cu")
		(at 394.208 -62.738 90)
		(property "Reference" "C2T12"
			(at 0 0 90)
			(layer "B.SilkS")
			(hide yes)
			(effects
				(font
					(size 1.27 1.27)
				)
				(justify mirror)
			)
		)
		(property "Value" ""
			(at 0 0 90)
			(layer "B.Fab")
			(effects
				(font
					(size 1.27 1.27)
				)
				(justify mirror)
			)
		)
		(duplicate_pad_numbers_are_jumpers no)
		(fp_poly
			(pts
				(xy -0.3048 -0.1016) (xy -0.3048 0.9906) (xy 0.3048 0.9906) (xy 0.3048 -0.1016)
			)
			(stroke
				(width 0)
				(type default)
			)
			(fill no)
			(layer "B.CrtYd")
		)
		(fp_line
			(start 0.3048 -0.1016)
			(end 0.3048 0.9906)
			(stroke
				(width 0.1)
				(type default)
			)
			(layer "B.Fab")
		)
		(fp_line
			(start -0.3048 -0.1016)
			(end 0.3048 -0.1016)
			(stroke
				(width 0.1)
				(type default)
			)
			(layer "B.Fab")
		)
		(fp_line
			(start 0.3048 0.9906)
			(end -0.3048 0.9906)
			(stroke
				(width 0.1)
				(type default)
			)
			(layer "B.Fab")
		)
		(fp_line
			(start -0.3048 0.9906)
			(end -0.3048 -0.1016)
			(stroke
				(width 0.1)
				(type default)
			)
			(layer "B.Fab")
		)
		(pad "1" smd rect
			(at 0 0 270)
			(size 0.508 0.508)
			(layers "B.Cu" "B.Mask" "B.Paste")
			(net "P3V3_STBY")
		)
		(pad "2" smd rect
			(at 0 0.889 270)
			(size 0.508 0.508)
			(layers "B.Cu" "B.Mask" "B.Paste")
			(net "GND")
		)
		(zone
			(layer "B.Cu")
			(hatch none 0.5)
			(connect_pads
				(clearance 0)
			)
			(min_thickness 0.25)
			(keepout
				(tracks allowed)
				(vias not_allowed)
				(pads allowed)
				(copperpour not_allowed)
				(footprints allowed)
			)
			(placement
				(enabled no)
				(sheetname "")
			)
			(fill
				(thermal_gap 0.5)
				(thermal_bridge_width 0.5)
				(island_removal_mode 0)
			)
			(polygon
				(pts
					(xy 394.462 -62.992) (xy 394.462 -62.484) (xy 394.843 -62.484) (xy 394.843 -62.992)
				)
			)
		)
		(zone
			(layer "B.Cu")
			(hatch none 0.5)
			(connect_pads
				(clearance 0)
			)
			(min_thickness 0.25)
			(keepout
				(tracks not_allowed)
				(vias allowed)
				(pads allowed)
				(copperpour not_allowed)
				(footprints allowed)
			)
			(placement
				(enabled no)
				(sheetname "")
			)
			(fill
				(thermal_gap 0.5)
				(thermal_bridge_width 0.5)
				(island_removal_mode 0)
			)
			(polygon
				(pts
					(xy 394.843 -62.992) (xy 394.843 -62.484) (xy 394.462 -62.484) (xy 394.462 -62.992)
				)
			)
		)
	)
	(footprint ""
		(layer "B.Cu")
		(at 348.713806 -60.368434)
		(property "Reference" "R2U25"
			(at 0 0 0)
			(layer "B.SilkS")
			(hide yes)
			(effects
				(font
					(size 1.27 1.27)
				)
				(justify mirror)
			)
		)
		(property "Value" ""
			(at 0 0 0)
			(layer "B.Fab")
			(effects
				(font
					(size 1.27 1.27)
				)
				(justify mirror)
			)
		)
		(duplicate_pad_numbers_are_jumpers no)
		(fp_poly
			(pts
				(xy 0.2794 -0.1016) (xy -0.2794 -0.1016) (xy -0.2794 0.9906) (xy 0.2794 0.9906)
			)
			(stroke
				(width 0)
				(type default)
			)
			(fill no)
			(layer "B.CrtYd")
		)
		(fp_line
			(start -0.2794 -0.1016)
			(end 0.2794 -0.1016)
			(stroke
				(width 0.1)
				(type default)
			)
			(layer "B.Fab")
		)
		(fp_line
			(start -0.2794 0.9906)
			(end -0.2794 -0.1016)
			(stroke
				(width 0.1)
				(type default)
			)
			(layer "B.Fab")
		)
		(fp_line
			(start 0.2794 -0.1016)
			(end 0.2794 0.9906)
			(stroke
				(width 0.1)
				(type default)
			)
			(layer "B.Fab")
		)
		(fp_line
			(start 0.2794 0.9906)
			(end -0.2794 0.9906)
			(stroke
				(width 0.1)
				(type default)
			)
			(layer "B.Fab")
		)
		(pad "1" smd rect
			(at 0 0 180)
			(size 0.508 0.508)
			(layers "B.Cu" "B.Mask" "B.Paste")
			(net "P3E_CPU0_PE1_SS_RXN<5>")
		)
		(pad "2" smd rect
			(at 0 0.889 180)
			(size 0.508 0.508)
			(layers "B.Cu" "B.Mask" "B.Paste")
			(net "P3E_CPU0_PE1_SS_R_RXN<5>")
		)
		(zone
			(layer "B.Cu")
			(hatch none 0.5)
			(connect_pads
				(clearance 0)
			)
			(min_thickness 0.25)
			(keepout
				(tracks allowed)
				(vias not_allowed)
				(pads allowed)
				(copperpour not_allowed)
				(footprints allowed)
			)
			(placement
				(enabled no)
				(sheetname "")
			)
			(fill
				(thermal_gap 0.5)
				(thermal_bridge_width 0.5)
				(island_removal_mode 0)
			)
			(polygon
				(pts
					(xy 348.967806 -60.114434) (xy 348.459806 -60.114434) (xy 348.459806 -59.733434) (xy 348.967806 -59.733434)
				)
			)
		)
	)
)
